# S9S_MB_2U (Grand Teton) — schematic netlist excerpt (pin names and nets, part order shuffled) for the footprints in the layout excerpt that follows; sources: Cadence DE-HDL packaged netlist, KiCad conversion of 03242023_DA0F0TMBIJ0_F0T_Motherboard_J_brd_V01_OCP.brd

R77  Q_RES  23.2K 1% CHIP  pkg 0402LF  page 108 : A = PD_CHF_CPU1_DIMM1_SAA ; B = GND

Q236  MOSFET_NCH_DUAL  PJT138K IC  pkg SOT363XD  page 260
  S1  = GND
  G1  = PWRGD_P5V
  D2  = PWRGD_P5V_ISO
  S2  = GND
  G2  = PWRGD_P5V_N
  D1  = PWRGD_P5V_N

(kicad_pcb
	(version 20260206)
	(generator "pcbnew")
	(generator_version "10.0")
	(general
		(thickness 1.6)
		(legacy_teardrops no)
	)
	(paper "A4")
	(title_block
		(title "03242023_DA0F0TMBIJ0_F0T_Motherboard_J_brd_V01_OCP.brd")
		(comment 1 "Grand Teton / footprints 4420-4421 of 6105")
	)
	(layers
		(0 "F.Cu" signal "TOP")
		(4 "In1.Cu" signal "GND")
		(6 "In2.Cu" signal "IN1")
		(8 "In3.Cu" signal "GND1")
		(10 "In4.Cu" signal "IN2")
		(12 "In5.Cu" signal "GND2")
		(14 "In6.Cu" signal "IN3")
		(16 "In7.Cu" signal "GND3")
		(18 "In8.Cu" signal "VCC")
		(20 "In9.Cu" signal "VCC1")
		(22 "In10.Cu" signal "GND4")
		(24 "In11.Cu" signal "IN4")
		(26 "In12.Cu" signal "GND5")
		(28 "In13.Cu" signal "IN5")
		(30 "In14.Cu" signal "GND6")
		(32 "In15.Cu" signal "IN6")
		(34 "In16.Cu" signal "GND7")
		(2 "B.Cu" signal "BOTTOM")
		(9 "F.Adhes" user "F.Adhesive")
		(11 "B.Adhes" user "B.Adhesive")
		(13 "F.Paste" user "Package Geometry/Pastemask Top")
		(15 "B.Paste" user "Package Geometry/Pastemask Bottom")
		(5 "F.SilkS" user "Ref Des/Silkscreen Top")
		(7 "B.SilkS" user "Ref Des/Silkscreen Bottom")
		(1 "F.Mask" user "Board Geometry/Soldermask Top")
		(3 "B.Mask" user "Board Geometry/Soldermask Bottom")
		(17 "Dwgs.User" user "User.Drawings")
		(19 "Cmts.User" user "User.Comments")
		(21 "Eco1.User" user "User.Eco1")
		(23 "Eco2.User" user "User.Eco2")
		(25 "Edge.Cuts" user "Board Geometry/Outline")
		(27 "Margin" user)
		(31 "F.CrtYd" user "Package Geometry/Place Bound Top")
		(29 "B.CrtYd" user "Package Geometry/Place Bound Bottom")
		(35 "F.Fab" user "Ref Des/Assembly Top")
		(33 "B.Fab" user "Ref Des/Assembly Bottom")
	)
	(footprint ""
		(layer "B.Cu")
		(at 434.86832 -47.98314 -90)
		(property "Reference" "Q236"
			(at 1.4224 -1.768348 270)
			(unlocked yes)
			(layer "B.SilkS")
			(effects
				(font
					(size 0.7874 0.5842)
					(thickness 0.1524)
				)
				(justify left mirror)
			)
		)
		(property "Value" ""
			(at 0 0 90)
			(layer "B.Fab")
			(effects
				(font
					(size 1.27 1.27)
				)
				(justify mirror)
			)
		)
		(duplicate_pad_numbers_are_jumpers no)
		(fp_line
			(start -1.332738 1.100074)
			(end 1.332738 1.100074)
			(stroke
				(width 0.1524)
				(type default)
			)
			(layer "B.SilkS")
		)
		(fp_line
			(start 1.332738 1.100074)
			(end 1.332738 -1.100074)
			(stroke
				(width 0.1524)
				(type default)
			)
			(layer "B.SilkS")
		)
		(fp_line
			(start 0 -0.541274)
			(end -0.4826 -1.100074)
			(stroke
				(width 0.1524)
				(type default)
			)
			(layer "B.SilkS")
		)
		(fp_line
			(start -1.332738 -1.100074)
			(end -1.332738 1.100074)
			(stroke
				(width 0.1524)
				(type default)
			)
			(layer "B.SilkS")
		)
		(fp_line
			(start -0.4826 -1.100074)
			(end -1.332738 -1.100074)
			(stroke
				(width 0.1524)
				(type default)
			)
			(layer "B.SilkS")
		)
		(fp_line
			(start 0.4826 -1.100074)
			(end 0 -0.541274)
			(stroke
				(width 0.1524)
				(type default)
			)
			(layer "B.SilkS")
		)
		(fp_line
			(start 1.332738 -1.100074)
			(end 0.4826 -1.100074)
			(stroke
				(width 0.1524)
				(type default)
			)
			(layer "B.SilkS")
		)
		(fp_poly
			(pts
				(xy 2.2352 -0.298958) (xy 2.2352 -1.001014) (xy 1.533144 -0.649986)
			)
			(stroke
				(width 0)
				(type default)
			)
			(fill yes)
			(layer "B.SilkS")
		)
		(fp_line
			(start -0.674878 1.100074)
			(end 0.674878 1.100074)
			(stroke
				(width 0.1)
				(type default)
			)
			(layer "B.Fab")
		)
		(fp_line
			(start 0.674878 1.100074)
			(end 0.674878 -1.100074)
			(stroke
				(width 0.1)
				(type default)
			)
			(layer "B.Fab")
		)
		(fp_line
			(start -0.674878 -1.100074)
			(end -0.674878 1.100074)
			(stroke
				(width 0.1)
				(type default)
			)
			(layer "B.Fab")
		)
		(fp_line
			(start 0.674878 -1.100074)
			(end -0.674878 -1.100074)
			(stroke
				(width 0.1)
				(type default)
			)
			(layer "B.Fab")
		)
		(fp_poly
			(pts
				(xy 2.2352 -0.298958) (xy 2.2352 -1.001014) (xy 1.533144 -0.649986)
			)
			(stroke
				(width 0)
				(type default)
			)
			(fill yes)
			(layer "B.Fab")
		)
		(pad "1" smd rect
			(at 0.94996 -0.649986)
			(size 0.4318 0.508)
			(layers "B.Cu" "B.Mask" "B.Paste")
			(net "GND")
		)
		(pad "2" smd rect
			(at 0.94996 0)
			(size 0.4318 0.508)
			(layers "B.Cu" "B.Mask" "B.Paste")
			(net "PWRGD_P5V")
		)
		(pad "3" smd rect
			(at 0.94996 0.649986)
			(size 0.4318 0.508)
			(layers "B.Cu" "B.Mask" "B.Paste")
			(net "PWRGD_P5V_ISO")
		)
		(pad "4" smd rect
			(at -0.94996 0.649986)
			(size 0.4318 0.508)
			(layers "B.Cu" "B.Mask" "B.Paste")
			(net "GND")
		)
		(pad "5" smd rect
			(at -0.94996 0)
			(size 0.4318 0.508)
			(layers "B.Cu" "B.Mask" "B.Paste")
			(net "PWRGD_P5V_N")
		)
		(pad "6" smd rect
			(at -0.94996 -0.649986)
			(size 0.4318 0.508)
			(layers "B.Cu" "B.Mask" "B.Paste")
			(net "PWRGD_P5V_N")
		)
	)
	(footprint ""
		(layer "B.Cu")
		(at 183.011826 -318.352424)
		(property "Reference" "R77"
			(at 0 0 0)
			(layer "B.SilkS")
			(hide yes)
			(effects
				(font
					(size 1.27 1.27)
				)
				(justify mirror)
			)
		)
		(property "Value" ""
			(at 0 0 0)
			(layer "B.Fab")
			(effects
				(font
					(size 1.27 1.27)
				)
				(justify mirror)
			)
		)
		(duplicate_pad_numbers_are_jumpers no)
		(fp_line
			(start -0.7874 -0.4064)
			(end -0.7874 0.4064)
			(stroke
				(width 0.1524)
				(type default)
			)
			(layer "B.SilkS")
		)
		(fp_line
			(start -0.7874 0.4064)
			(end 0.7874 0.4064)
			(stroke
				(width 0.1524)
				(type default)
			)
			(layer "B.SilkS")
		)
		(fp_line
			(start 0.7874 -0.4064)
			(end -0.7874 -0.4064)
			(stroke
				(width 0.1524)
				(type default)
			)
			(layer "B.SilkS")
		)
		(fp_line
			(start 0.7874 0.4064)
			(end 0.7874 -0.4064)
			(stroke
				(width 0.1524)
				(type default)
			)
			(layer "B.SilkS")
		)
		(fp_line
			(start -0.67945 -0.3048)
			(end -0.67945 0.3048)
			(stroke
				(width 0.1)
				(type default)
			)
			(layer "B.Fab")
		)
		(fp_line
			(start -0.67945 0.3048)
			(end -0.120396 0.3048)
			(stroke
				(width 0.1)
				(type default)
			)
			(layer "B.Fab")
		)
		(fp_line
			(start -0.12065 -0.3048)
			(end -0.67945 -0.3048)
			(stroke
				(width 0.1)
				(type default)
			)
			(layer "B.Fab")
		)
		(fp_line
			(start -0.12065 -0.2794)
			(end -0.12065 -0.3048)
			(stroke
				(width 0.1)
				(type default)
			)
			(layer "B.Fab")
		)
		(fp_line
			(start -0.120396 0.2794)
			(end 0.12065 0.2794)
			(stroke
				(width 0.1)
				(type default)
			)
			(layer "B.Fab")
		)
		(fp_line
			(start -0.120396 0.3048)
			(end -0.120396 0.2794)
			(stroke
				(width 0.1)
				(type default)
			)
			(layer "B.Fab")
		)
		(fp_line
			(start 0.12065 -0.305054)
			(end 0.12065 -0.2794)
			(stroke
				(width 0.1)
				(type default)
			)
			(layer "B.Fab")
		)
		(fp_line
			(start 0.12065 -0.2794)
			(end -0.12065 -0.2794)
			(stroke
				(width 0.1)
				(type default)
			)
			(layer "B.Fab")
		)
		(fp_line
			(start 0.12065 0.2794)
			(end 0.12065 0.3048)
			(stroke
				(width 0.1)
				(type default)
			)
			(layer "B.Fab")
		)
		(fp_line
			(start 0.12065 0.3048)
			(end 0.67945 0.3048)
			(stroke
				(width 0.1)
				(type default)
			)
			(layer "B.Fab")
		)
		(fp_line
			(start 0.67945 -0.305054)
			(end 0.12065 -0.305054)
			(stroke
				(width 0.1)
				(type default)
			)
			(layer "B.Fab")
		)
		(fp_line
			(start 0.67945 0.3048)
			(end 0.67945 -0.305054)
			(stroke
				(width 0.1)
				(type default)
			)
			(layer "B.Fab")
		)
		(pad "1" smd circle
			(at 0.40005 0 180)
			(size 0 0)
			(layers "B.Cu" "B.Mask" "B.Paste")
			(net "PD_CHF_CPU1_DIMM1_SAA")
		)
		(pad "2" smd circle
			(at -0.40005 0 180)
			(size 0 0)
			(layers "B.Cu" "B.Mask" "B.Paste")
			(net "GND")
		)
	)
)
